(kicad_pcb
	(version 20260206)
	(generator "pcbnew")
	(generator_version "10.0")
	(general
		(thickness 1.6)
		(legacy_teardrops no)
	)
	(paper "A4")
	(title_block
		(title "Bryce Canyon_IOM_IOC_16318-2_OCP.brd")
		(comment 1 "Bryce Canyon / footprints 531-538 of 1605")
	)
	(layers
		(0 "F.Cu" signal "TOP")
		(4 "In1.Cu" signal "L2GND")
		(6 "In2.Cu" signal "L3")
		(8 "In3.Cu" signal "L4VCC")
		(10 "In4.Cu" signal "L5VCC")
		(12 "In5.Cu" signal "L6")
		(14 "In6.Cu" signal "L7GND")
		(2 "B.Cu" signal "BOTTOM")
		(9 "F.Adhes" user "F.Adhesive")
		(11 "B.Adhes" user "B.Adhesive")
		(13 "F.Paste" user "Package Geometry/Pastemask Top")
		(15 "B.Paste" user "Package Geometry/Pastemask Bottom")
		(5 "F.SilkS" user "Ref Des/Silkscreen Top")
		(7 "B.SilkS" user "Ref Des/Silkscreen Bottom")
		(1 "F.Mask" user "Board Geometry/Soldermask Top")
		(3 "B.Mask" user "Board Geometry/Soldermask Bottom")
		(17 "Dwgs.User" user "User.Drawings")
		(19 "Cmts.User" user "User.Comments")
		(21 "Eco1.User" user "User.Eco1")
		(23 "Eco2.User" user "User.Eco2")
		(25 "Edge.Cuts" user "Board Geometry/Outline")
		(27 "Margin" user)
		(31 "F.CrtYd" user "Package Geometry/Place Bound Top")
		(29 "B.CrtYd" user "Package Geometry/Place Bound Bottom")
		(35 "F.Fab" user "Ref Des/Assembly Top")
		(33 "B.Fab" user "Ref Des/Assembly Bottom")
	)
	(footprint ""
		(layer "F.Cu")
		(at 58.3946 -159.1818)
		(property "Reference" "R391"
			(at 0 0 0)
			(layer "F.SilkS")
			(hide yes)
			(effects
				(font
					(size 1.27 1.27)
				)
			)
		)
		(property "Value" "4K7R2F-GP"
			(at 0.064008 -3.993896 0)
			(unlocked yes)
			(layer "F.Fab")
			(hide yes)
			(effects
				(font
					(size 1.016 1.016)
					(thickness 0.1524)
				)
			)
		)
		(property "Device Type" "R402H16"
			(at 0.064008 -5.517896 0)
			(unlocked yes)
			(layer "F.Fab")
			(hide yes)
			(effects
				(font
					(size 1.016 1.016)
					(thickness 0.1524)
				)
			)
		)
		(duplicate_pad_numbers_are_jumpers no)
		(fp_line
			(start -0.508 -0.9398)
			(end -0.508 0.9398)
			(stroke
				(width 0.1524)
				(type default)
			)
			(layer "F.SilkS")
		)
		(fp_line
			(start 0.508 -0.9398)
			(end -0.508 -0.9398)
			(stroke
				(width 0.1524)
				(type default)
			)
			(layer "F.SilkS")
		)
		(fp_rect
			(start -0.508 0.9398)
			(end 0.508 -0.9398)
			(stroke
				(width 0)
				(type default)
			)
			(fill no)
			(layer "F.CrtYd")
		)
		(fp_rect
			(start -0.508 0.9398)
			(end 0.508 -0.9398)
			(stroke
				(width 0)
				(type default)
			)
			(fill no)
			(layer "F.Fab")
		)
		(pad "1" smd custom
			(at 0 -0.4445)
			(size 0.1397 0.1397)
			(layers "F.Cu" "F.Mask" "F.Paste")
			(net "P3V3_STBY")
			(options
				(clearance outline)
				(anchor circle)
			)
			(primitives
				(gr_poly
					(pts
						(arc
							(start -0.1778 -0.2794)
							(mid -0.249642 -0.249642)
							(end -0.2794 -0.1778)
						)
						(arc
							(start -0.2794 0.1778)
							(mid -0.249642 0.249642)
							(end -0.1778 0.2794)
						)
						(arc
							(start 0.1778 0.2794)
							(mid 0.249642 0.249642)
							(end 0.2794 0.1778)
						)
						(arc
							(start 0.2794 -0.1778)
							(mid 0.249642 -0.249642)
							(end 0.1778 -0.2794)
						)
					)
					(width 0)
					(fill yes)
				)
			)
		)
		(pad "2" smd custom
			(at 0 0.4445)
			(size 0.1397 0.1397)
			(layers "F.Cu" "F.Mask" "F.Paste")
			(net "MAC2_TXD0")
			(options
				(clearance outline)
				(anchor circle)
			)
			(primitives
				(gr_poly
					(pts
						(arc
							(start -0.1778 -0.2794)
							(mid -0.249642 -0.249642)
							(end -0.2794 -0.1778)
						)
						(arc
							(start -0.2794 0.1778)
							(mid -0.249642 0.249642)
							(end -0.1778 0.2794)
						)
						(arc
							(start 0.1778 0.2794)
							(mid 0.249642 0.249642)
							(end 0.2794 0.1778)
						)
						(arc
							(start 0.2794 -0.1778)
							(mid 0.249642 -0.249642)
							(end 0.1778 -0.2794)
						)
					)
					(width 0)
					(fill yes)
				)
			)
		)
	)
	(footprint ""
		(layer "F.Cu")
		(at 111.0742 -12.079478 -90)
		(property "Reference" "C147"
			(at 0 0 270)
			(layer "F.SilkS")
			(hide yes)
			(effects
				(font
					(size 1.27 1.27)
				)
			)
		)
		(property "Value" "SC1U16V3KX-5GP"
			(at 0 -2.8194 270)
			(unlocked yes)
			(layer "F.Fab")
			(hide yes)
			(effects
				(font
					(size 1.016 1.016)
					(thickness 0.1524)
				)
			)
		)
		(property "Device Type" "C603H36"
			(at 0 -4.3434 270)
			(unlocked yes)
			(layer "F.Fab")
			(hide yes)
			(effects
				(font
					(size 1.016 1.016)
					(thickness 0.1524)
				)
			)
		)
		(duplicate_pad_numbers_are_jumpers no)
		(fp_line
			(start 0.508 0)
			(end -0.508 0)
			(stroke
				(width 0.2032)
				(type default)
			)
			(layer "F.SilkS")
		)
		(fp_rect
			(start -0.5842 1.3335)
			(end 0.5842 -1.3335)
			(stroke
				(width 0)
				(type default)
			)
			(fill no)
			(layer "F.CrtYd")
		)
		(fp_rect
			(start -0.5842 1.3335)
			(end 0.5842 -1.3335)
			(stroke
				(width 0)
				(type default)
			)
			(fill no)
			(layer "F.Fab")
		)
		(pad "1" smd custom
			(at 0 -0.762 270)
			(size 0.2159 0.2159)
			(layers "F.Cu" "F.Mask" "F.Paste")
			(net "MB0_VCAP_R")
			(options
				(clearance outline)
				(anchor circle)
			)
			(primitives
				(gr_poly
					(pts
						(arc
							(start -0.3302 -0.4318)
							(mid -0.402042 -0.402042)
							(end -0.4318 -0.3302)
						)
						(arc
							(start -0.4318 0.3302)
							(mid -0.402042 0.402042)
							(end -0.3302 0.4318)
						)
						(arc
							(start 0.3302 0.4318)
							(mid 0.402042 0.402042)
							(end 0.4318 0.3302)
						)
						(arc
							(start 0.4318 -0.3302)
							(mid 0.402042 -0.402042)
							(end 0.3302 -0.4318)
						)
					)
					(width 0)
					(fill yes)
				)
			)
		)
		(pad "2" smd custom
			(at 0 0.762 270)
			(size 0.2159 0.2159)
			(layers "F.Cu" "F.Mask" "F.Paste")
			(net "AGND_CURRENT_MON")
			(options
				(clearance outline)
				(anchor circle)
			)
			(primitives
				(gr_poly
					(pts
						(arc
							(start -0.3302 -0.4318)
							(mid -0.402042 -0.402042)
							(end -0.4318 -0.3302)
						)
						(arc
							(start -0.4318 0.3302)
							(mid -0.402042 0.402042)
							(end -0.3302 0.4318)
						)
						(arc
							(start 0.3302 0.4318)
							(mid 0.402042 0.402042)
							(end 0.4318 0.3302)
						)
						(arc
							(start 0.4318 -0.3302)
							(mid 0.402042 -0.402042)
							(end 0.3302 -0.4318)
						)
					)
					(width 0)
					(fill yes)
				)
			)
		)
	)
	(footprint ""
		(layer "F.Cu")
		(at 66.802 -172.085)
		(property "Reference" "C34"
			(at 0 0 0)
			(layer "F.SilkS")
			(hide yes)
			(effects
				(font
					(size 1.27 1.27)
				)
			)
		)
		(property "Value" "SCD1U16V2KX-3GP"
			(at 1.1811 -2.7051 0)
			(unlocked yes)
			(layer "F.Fab")
			(hide yes)
			(effects
				(font
					(size 1.016 1.016)
					(thickness 0.1524)
				)
			)
		)
		(property "Device Type" "C402H22"
			(at 1.1811 -4.2291 0)
			(unlocked yes)
			(layer "F.Fab")
			(hide yes)
			(effects
				(font
					(size 1.016 1.016)
					(thickness 0.1524)
				)
			)
		)
		(duplicate_pad_numbers_are_jumpers no)
		(fp_rect
			(start -0.4318 0.9525)
			(end 0.4318 -0.9525)
			(stroke
				(width 0)
				(type default)
			)
			(fill no)
			(layer "F.CrtYd")
		)
		(fp_rect
			(start -0.4318 0.9525)
			(end 0.4318 -0.9525)
			(stroke
				(width 0)
				(type default)
			)
			(fill no)
			(layer "F.Fab")
		)
		(pad "1" smd custom
			(at 0 -0.4445)
			(size 0.1524 0.1524)
			(layers "F.Cu" "F.Mask" "F.Paste")
			(net "P5V_STBY")
			(options
				(clearance outline)
				(anchor circle)
			)
			(primitives
				(gr_poly
					(pts
						(arc
							(start 0.3048 -0.2032)
							(mid 0.275042 -0.275042)
							(end 0.2032 -0.3048)
						)
						(arc
							(start -0.2032 -0.3048)
							(mid -0.275042 -0.275042)
							(end -0.3048 -0.2032)
						)
						(arc
							(start -0.3048 0.2032)
							(mid -0.275042 0.275042)
							(end -0.2032 0.3048)
						)
						(arc
							(start 0.2032 0.3048)
							(mid 0.275042 0.275042)
							(end 0.3048 0.2032)
						)
					)
					(width 0)
					(fill yes)
				)
			)
		)
		(pad "2" smd custom
			(at 0 0.4445)
			(size 0.1524 0.1524)
			(layers "F.Cu" "F.Mask" "F.Paste")
			(net "GND")
			(options
				(clearance outline)
				(anchor circle)
			)
			(primitives
				(gr_poly
					(pts
						(arc
							(start 0.3048 -0.2032)
							(mid 0.275042 -0.275042)
							(end 0.2032 -0.3048)
						)
						(arc
							(start -0.2032 -0.3048)
							(mid -0.275042 -0.275042)
							(end -0.3048 -0.2032)
						)
						(arc
							(start -0.3048 0.2032)
							(mid -0.275042 0.275042)
							(end -0.2032 0.3048)
						)
						(arc
							(start 0.2032 0.3048)
							(mid 0.275042 0.275042)
							(end 0.3048 0.2032)
						)
					)
					(width 0)
					(fill yes)
				)
			)
		)
	)
	(footprint ""
		(layer "F.Cu")
		(at 131.230878 -6.462776 -90)
		(property "Reference" "R450"
			(at 0 0 270)
			(layer "F.SilkS")
			(hide yes)
			(effects
				(font
					(size 1.27 1.27)
				)
			)
		)
		(property "Value" "10R5F-1-GP"
			(at 0 -8.9535 270)
			(unlocked yes)
			(layer "F.Fab")
			(hide yes)
			(effects
				(font
					(size 1.27 1.016)
					(thickness 0.1524)
				)
			)
		)
		(property "Device Type" "R805H24"
			(at 0 -10.6299 270)
			(unlocked yes)
			(layer "F.Fab")
			(hide yes)
			(effects
				(font
					(size 1.27 1.016)
					(thickness 0.1524)
				)
			)
		)
		(duplicate_pad_numbers_are_jumpers no)
		(fp_line
			(start -0.889 1.7018)
			(end 0.889 1.7018)
			(stroke
				(width 0.1524)
				(type default)
			)
			(layer "F.SilkS")
		)
		(fp_line
			(start 0.889 1.7018)
			(end 0.889 -0.508)
			(stroke
				(width 0.1524)
				(type default)
			)
			(layer "F.SilkS")
		)
		(fp_line
			(start -0.889 0.0762)
			(end -0.889 1.7018)
			(stroke
				(width 0.1524)
				(type default)
			)
			(layer "F.SilkS")
		)
		(fp_line
			(start -0.889 -1.7018)
			(end -0.889 0.2794)
			(stroke
				(width 0.1524)
				(type default)
			)
			(layer "F.SilkS")
		)
		(fp_line
			(start 0.889 -1.7018)
			(end 0.889 -0.381)
			(stroke
				(width 0.1524)
				(type default)
			)
			(layer "F.SilkS")
		)
		(fp_line
			(start 0.889 -1.7018)
			(end -0.889 -1.7018)
			(stroke
				(width 0.1524)
				(type default)
			)
			(layer "F.SilkS")
		)
		(fp_poly
			(pts
				(xy 0.9652 -1.778) (xy 0.9652 1.778) (xy -0.9652 1.778) (xy -0.9652 -1.778)
			)
			(stroke
				(width 0)
				(type default)
			)
			(fill no)
			(layer "F.CrtYd")
		)
		(fp_rect
			(start -0.9652 1.778)
			(end 0.9652 -1.778)
			(stroke
				(width 0)
				(type default)
			)
			(fill no)
			(layer "F.Fab")
		)
		(pad "1" smd rect
			(at 0 -0.9652 270)
			(size 1.397 1.143)
			(layers "F.Cu" "F.Mask" "F.Paste")
			(net "MB0_12V_CTRL_GATE1")
		)
		(pad "2" smd rect
			(at 0 0.9652 270)
			(size 1.397 1.143)
			(layers "F.Cu" "F.Mask" "F.Paste")
			(net "MB0_CM_GATE_R")
		)
	)
	(footprint ""
		(layer "F.Cu")
		(at 74.46137 -138.914124 -90)
		(property "Reference" "R51"
			(at 0 0 270)
			(layer "F.SilkS")
			(hide yes)
			(effects
				(font
					(size 1.27 1.27)
				)
			)
		)
		(property "Value" "33R2F-3-GP"
			(at 0.064008 -3.993896 270)
			(unlocked yes)
			(layer "F.Fab")
			(hide yes)
			(effects
				(font
					(size 1.016 1.016)
					(thickness 0.1524)
				)
			)
		)
		(property "Device Type" "R402H16"
			(at 0.064008 -5.517896 270)
			(unlocked yes)
			(layer "F.Fab")
			(hide yes)
			(effects
				(font
					(size 1.016 1.016)
					(thickness 0.1524)
				)
			)
		)
		(duplicate_pad_numbers_are_jumpers no)
		(fp_line
			(start -0.508 -0.9398)
			(end -0.508 0.9398)
			(stroke
				(width 0.1524)
				(type default)
			)
			(layer "F.SilkS")
		)
		(fp_line
			(start 0.508 -0.9398)
			(end -0.508 -0.9398)
			(stroke
				(width 0.1524)
				(type default)
			)
			(layer "F.SilkS")
		)
		(fp_rect
			(start -0.508 0.9398)
			(end 0.508 -0.9398)
			(stroke
				(width 0)
				(type default)
			)
			(fill no)
			(layer "F.CrtYd")
		)
		(fp_rect
			(start -0.508 0.9398)
			(end 0.508 -0.9398)
			(stroke
				(width 0)
				(type default)
			)
			(fill no)
			(layer "F.Fab")
		)
		(pad "1" smd custom
			(at 0 -0.4445 270)
			(size 0.1397 0.1397)
			(layers "F.Cu" "F.Mask" "F.Paste")
			(net "FP_PWR_BTN_N")
			(options
				(clearance outline)
				(anchor circle)
			)
			(primitives
				(gr_poly
					(pts
						(arc
							(start -0.1778 -0.2794)
							(mid -0.249642 -0.249642)
							(end -0.2794 -0.1778)
						)
						(arc
							(start -0.2794 0.1778)
							(mid -0.249642 0.249642)
							(end -0.1778 0.2794)
						)
						(arc
							(start 0.1778 0.2794)
							(mid 0.249642 0.249642)
							(end 0.2794 0.1778)
						)
						(arc
							(start 0.2794 -0.1778)
							(mid 0.249642 -0.249642)
							(end 0.1778 -0.2794)
						)
					)
					(width 0)
					(fill yes)
				)
			)
		)
		(pad "2" smd custom
			(at 0 0.4445 270)
			(size 0.1397 0.1397)
			(layers "F.Cu" "F.Mask" "F.Paste")
			(net "FP_PWR_BTN_N_R")
			(options
				(clearance outline)
				(anchor circle)
			)
			(primitives
				(gr_poly
					(pts
						(arc
							(start -0.1778 -0.2794)
							(mid -0.249642 -0.249642)
							(end -0.2794 -0.1778)
						)
						(arc
							(start -0.2794 0.1778)
							(mid -0.249642 0.249642)
							(end -0.1778 0.2794)
						)
						(arc
							(start 0.1778 0.2794)
							(mid 0.249642 0.249642)
							(end 0.2794 0.1778)
						)
						(arc
							(start 0.2794 -0.1778)
							(mid 0.249642 -0.249642)
							(end 0.1778 -0.2794)
						)
					)
					(width 0)
					(fill yes)
				)
			)
		)
	)
	(footprint ""
		(layer "F.Cu")
		(at 23.756874 -125.638814 180)
		(property "Reference" "R346"
			(at 0 0 180)
			(layer "F.SilkS")
			(hide yes)
			(effects
				(font
					(size 1.27 1.27)
				)
			)
		)
		(property "Value" "150R2F-1-GP"
			(at 0.064008 -3.993896 180)
			(unlocked yes)
			(layer "F.Fab")
			(hide yes)
			(effects
				(font
					(size 1.016 1.016)
					(thickness 0.1524)
				)
			)
		)
		(property "Device Type" "R402H16"
			(at 0.064008 -5.517896 180)
			(unlocked yes)
			(layer "F.Fab")
			(hide yes)
			(effects
				(font
					(size 1.016 1.016)
					(thickness 0.1524)
				)
			)
		)
		(duplicate_pad_numbers_are_jumpers no)
		(fp_line
			(start 0.508 -0.9398)
			(end -0.508 -0.9398)
			(stroke
				(width 0.1524)
				(type default)
			)
			(layer "F.SilkS")
		)
		(fp_line
			(start -0.508 -0.9398)
			(end -0.508 0.9398)
			(stroke
				(width 0.1524)
				(type default)
			)
			(layer "F.SilkS")
		)
		(fp_rect
			(start -0.508 0.9398)
			(end 0.508 -0.9398)
			(stroke
				(width 0)
				(type default)
			)
			(fill no)
			(layer "F.CrtYd")
		)
		(fp_rect
			(start -0.508 0.9398)
			(end 0.508 -0.9398)
			(stroke
				(width 0)
				(type default)
			)
			(fill no)
			(layer "F.Fab")
		)
		(pad "1" smd custom
			(at 0 -0.4445 180)
			(size 0.1397 0.1397)
			(layers "F.Cu" "F.Mask" "F.Paste")
			(net "P3V3_STBY")
			(options
				(clearance outline)
				(anchor circle)
			)
			(primitives
				(gr_poly
					(pts
						(arc
							(start -0.1778 -0.2794)
							(mid -0.249642 -0.249642)
							(end -0.2794 -0.1778)
						)
						(arc
							(start -0.2794 0.1778)
							(mid -0.249642 0.249642)
							(end -0.1778 0.2794)
						)
						(arc
							(start 0.1778 0.2794)
							(mid 0.249642 0.249642)
							(end 0.2794 0.1778)
						)
						(arc
							(start 0.2794 -0.1778)
							(mid 0.249642 -0.249642)
							(end 0.1778 -0.2794)
						)
					)
					(width 0)
					(fill yes)
				)
			)
		)
		(pad "2" smd custom
			(at 0 0.4445 180)
			(size 0.1397 0.1397)
			(layers "F.Cu" "F.Mask" "F.Paste")
			(net "BMC_HBLED_R")
			(options
				(clearance outline)
				(anchor circle)
			)
			(primitives
				(gr_poly
					(pts
						(arc
							(start -0.1778 -0.2794)
							(mid -0.249642 -0.249642)
							(end -0.2794 -0.1778)
						)
						(arc
							(start -0.2794 0.1778)
							(mid -0.249642 0.249642)
							(end -0.1778 0.2794)
						)
						(arc
							(start 0.1778 0.2794)
							(mid 0.249642 0.249642)
							(end 0.2794 0.1778)
						)
						(arc
							(start 0.2794 -0.1778)
							(mid 0.249642 -0.249642)
							(end 0.1778 -0.2794)
						)
					)
					(width 0)
					(fill yes)
				)
			)
		)
	)
	(footprint ""
		(layer "F.Cu")
		(at 61.543184 -143.458692 90)
		(property "Reference" "R157"
			(at 0 0 90)
			(layer "F.SilkS")
			(hide yes)
			(effects
				(font
					(size 1.27 1.27)
				)
			)
		)
		(property "Value" "0R2J-2-GP"
			(at 0.064008 -3.993896 90)
			(unlocked yes)
			(layer "F.Fab")
			(hide yes)
			(effects
				(font
					(size 1.016 1.016)
					(thickness 0.1524)
				)
			)
		)
		(property "Device Type" "R402H16"
			(at 0.064008 -5.517896 90)
			(unlocked yes)
			(layer "F.Fab")
			(hide yes)
			(effects
				(font
					(size 1.016 1.016)
					(thickness 0.1524)
				)
			)
		)
		(duplicate_pad_numbers_are_jumpers no)
		(fp_line
			(start 0.508 -0.9398)
			(end -0.508 -0.9398)
			(stroke
				(width 0.1524)
				(type default)
			)
			(layer "F.SilkS")
		)
		(fp_line
			(start -0.508 -0.9398)
			(end -0.508 0.9398)
			(stroke
				(width 0.1524)
				(type default)
			)
			(layer "F.SilkS")
		)
		(fp_rect
			(start -0.508 0.9398)
			(end 0.508 -0.9398)
			(stroke
				(width 0)
				(type default)
			)
			(fill no)
			(layer "F.CrtYd")
		)
		(fp_rect
			(start -0.508 0.9398)
			(end 0.508 -0.9398)
			(stroke
				(width 0)
				(type default)
			)
			(fill no)
			(layer "F.Fab")
		)
		(pad "1" smd custom
			(at 0 -0.4445 90)
			(size 0.1397 0.1397)
			(layers "F.Cu" "F.Mask" "F.Paste")
			(net "BMC_SMB11_DAT")
			(options
				(clearance outline)
				(anchor circle)
			)
			(primitives
				(gr_poly
					(pts
						(arc
							(start -0.1778 -0.2794)
							(mid -0.249642 -0.249642)
							(end -0.2794 -0.1778)
						)
						(arc
							(start -0.2794 0.1778)
							(mid -0.249642 0.249642)
							(end -0.1778 0.2794)
						)
						(arc
							(start 0.1778 0.2794)
							(mid 0.249642 0.249642)
							(end 0.2794 0.1778)
						)
						(arc
							(start 0.2794 -0.1778)
							(mid 0.249642 -0.249642)
							(end 0.1778 -0.2794)
						)
					)
					(width 0)
					(fill yes)
				)
			)
		)
		(pad "2" smd custom
			(at 0 0.4445 90)
			(size 0.1397 0.1397)
			(layers "F.Cu" "F.Mask" "F.Paste")
			(net "I2C_EXP_RMT_SDA_OUT")
			(options
				(clearance outline)
				(anchor circle)
			)
			(primitives
				(gr_poly
					(pts
						(arc
							(start -0.1778 -0.2794)
							(mid -0.249642 -0.249642)
							(end -0.2794 -0.1778)
						)
						(arc
							(start -0.2794 0.1778)
							(mid -0.249642 0.249642)
							(end -0.1778 0.2794)
						)
						(arc
							(start 0.1778 0.2794)
							(mid 0.249642 0.249642)
							(end 0.2794 0.1778)
						)
						(arc
							(start 0.2794 -0.1778)
							(mid 0.249642 -0.249642)
							(end 0.1778 -0.2794)
						)
					)
					(width 0)
					(fill yes)
				)
			)
		)
	)
	(footprint ""
		(layer "F.Cu")
		(at 200.7362 -113.5126 180)
		(property "Reference" "C259"
			(at 0 0 180)
			(layer "F.SilkS")
			(hide yes)
			(effects
				(font
					(size 1.27 1.27)
				)
			)
		)
		(property "Value" "SC22U6D3V6KX-2-GP"
			(at -0.0762 -5.1308 180)
			(unlocked yes)
			(layer "F.Fab")
			(hide yes)
			(effects
				(font
					(size 1.016 1.016)
					(thickness 0.1524)
				)
			)
		)
		(property "Device Type" "C1206H71"
			(at -0.127 -6.6548 180)
			(unlocked yes)
			(layer "F.Fab")
			(hide yes)
			(effects
				(font
					(size 1.016 1.016)
					(thickness 0.1524)
				)
			)
		)
		(duplicate_pad_numbers_are_jumpers no)
		(fp_line
			(start 1.016 2.2352)
			(end -1.016 2.2352)
			(stroke
				(width 0.1524)
				(type default)
			)
			(layer "F.SilkS")
		)
		(fp_line
			(start 1.016 0.8382)
			(end 1.016 2.2352)
			(stroke
				(width 0.1524)
				(type default)
			)
			(layer "F.SilkS")
		)
		(fp_line
			(start 1.016 -2.2352)
			(end 1.016 -0.8382)
			(stroke
				(width 0.1524)
				(type default)
			)
			(layer "F.SilkS")
		)
		(fp_line
			(start -1.016 2.2352)
			(end -1.016 0.8382)
			(stroke
				(width 0.1524)
				(type default)
			)
			(layer "F.SilkS")
		)
		(fp_line
			(start -1.016 -0.8382)
			(end -1.016 -2.2352)
			(stroke
				(width 0.1524)
				(type default)
			)
			(layer "F.SilkS")
		)
		(fp_line
			(start -1.016 -2.2352)
			(end 1.016 -2.2352)
			(stroke
				(width 0.1524)
				(type default)
			)
			(layer "F.SilkS")
		)
		(fp_rect
			(start -1.0922 2.3114)
			(end 1.0922 -2.3114)
			(stroke
				(width 0)
				(type default)
			)
			(fill no)
			(layer "F.CrtYd")
		)
		(fp_poly
			(pts
				(xy 1.0922 -2.3114) (xy 1.0922 2.3114) (xy -1.0922 2.3114) (xy -1.0922 -2.3114)
			)
			(stroke
				(width 0)
				(type default)
			)
			(fill no)
			(layer "F.Fab")
		)
		(pad "1" smd rect
			(at 0 -1.397 180)
			(size 1.651 1.27)
			(layers "F.Cu" "F.Mask" "F.Paste")
			(net "P0V975")
		)
		(pad "2" smd rect
			(at 0 1.397 180)
			(size 1.651 1.27)
			(layers "F.Cu" "F.Mask" "F.Paste")
			(net "GND")
		)
	)
)
